# S9S_MB_2U (Grand Teton) — schematic netlist excerpt (pin names and nets, part order shuffled) for the footprints in the layout excerpt that follows; sources: Cadence DE-HDL packaged netlist, KiCad conversion of 03242023_DA0F0TMBIJ0_F0T_Motherboard_J_brd_V01_OCP.brd

R299  Q_RES  0 5% CHIP  pkg 0402LF  page 118 : A = H_CPU1_CATERR_LVC1_R_N ; B = H_CPU_CATERR_LVC1_R_N
C1906  Q_CAP  0.1UF 25V 10% X7R  pkg 0402  page 217 : A = P3V3_AUX_FPGA_VCCIO1 ; B = GND

(kicad_pcb
	(version 20260206)
	(generator "pcbnew")
	(generator_version "10.0")
	(general
		(thickness 1.6)
		(legacy_teardrops no)
	)
	(paper "A4")
	(title_block
		(title "03242023_DA0F0TMBIJ0_F0T_Motherboard_J_brd_V01_OCP.brd")
		(comment 1 "Grand Teton / footprints 4265-4266 of 6105")
	)
	(layers
		(0 "F.Cu" signal "TOP")
		(4 "In1.Cu" signal "GND")
		(6 "In2.Cu" signal "IN1")
		(8 "In3.Cu" signal "GND1")
		(10 "In4.Cu" signal "IN2")
		(12 "In5.Cu" signal "GND2")
		(14 "In6.Cu" signal "IN3")
		(16 "In7.Cu" signal "GND3")
		(18 "In8.Cu" signal "VCC")
		(20 "In9.Cu" signal "VCC1")
		(22 "In10.Cu" signal "GND4")
		(24 "In11.Cu" signal "IN4")
		(26 "In12.Cu" signal "GND5")
		(28 "In13.Cu" signal "IN5")
		(30 "In14.Cu" signal "GND6")
		(32 "In15.Cu" signal "IN6")
		(34 "In16.Cu" signal "GND7")
		(2 "B.Cu" signal "BOTTOM")
		(9 "F.Adhes" user "F.Adhesive")
		(11 "B.Adhes" user "B.Adhesive")
		(13 "F.Paste" user "Package Geometry/Pastemask Top")
		(15 "B.Paste" user "Package Geometry/Pastemask Bottom")
		(5 "F.SilkS" user "Ref Des/Silkscreen Top")
		(7 "B.SilkS" user "Ref Des/Silkscreen Bottom")
		(1 "F.Mask" user "Board Geometry/Soldermask Top")
		(3 "B.Mask" user "Board Geometry/Soldermask Bottom")
		(17 "Dwgs.User" user "User.Drawings")
		(19 "Cmts.User" user "User.Comments")
		(21 "Eco1.User" user "User.Eco1")
		(23 "Eco2.User" user "User.Eco2")
		(25 "Edge.Cuts" user "Board Geometry/Outline")
		(27 "Margin" user)
		(31 "F.CrtYd" user "Package Geometry/Place Bound Top")
		(29 "B.CrtYd" user "Package Geometry/Place Bound Bottom")
		(35 "F.Fab" user "Ref Des/Assembly Top")
		(33 "B.Fab" user "Ref Des/Assembly Bottom")
	)
	(footprint ""
		(layer "B.Cu")
		(at 180.555646 -115.775486 90)
		(property "Reference" "C1906"
			(at 0 0 90)
			(layer "B.SilkS")
			(hide yes)
			(effects
				(font
					(size 1.27 1.27)
				)
				(justify mirror)
			)
		)
		(property "Value" ""
			(at 0 0 90)
			(layer "B.Fab")
			(effects
				(font
					(size 1.27 1.27)
				)
				(justify mirror)
			)
		)
		(duplicate_pad_numbers_are_jumpers no)
		(fp_line
			(start 0.69215 -0.2921)
			(end -0.69215 -0.2921)
			(stroke
				(width 0.1524)
				(type default)
			)
			(layer "B.SilkS")
		)
		(fp_line
			(start -0.69215 -0.2921)
			(end -0.69215 0.2921)
			(stroke
				(width 0.1524)
				(type default)
			)
			(layer "B.SilkS")
		)
		(fp_line
			(start 0.69215 0.2921)
			(end 0.69215 -0.2921)
			(stroke
				(width 0.1524)
				(type default)
			)
			(layer "B.SilkS")
		)
		(fp_line
			(start -0.69215 0.2921)
			(end 0.69215 0.2921)
			(stroke
				(width 0.1524)
				(type default)
			)
			(layer "B.SilkS")
		)
		(fp_line
			(start 0.51435 -0.2794)
			(end -0.51435 -0.2794)
			(stroke
				(width 0.1)
				(type default)
			)
			(layer "B.Fab")
		)
		(fp_line
			(start -0.51435 -0.2794)
			(end -0.51435 0.2794)
			(stroke
				(width 0.1)
				(type default)
			)
			(layer "B.Fab")
		)
		(fp_line
			(start 0.51435 0.2794)
			(end 0.51435 -0.2794)
			(stroke
				(width 0.1)
				(type default)
			)
			(layer "B.Fab")
		)
		(fp_line
			(start -0.51435 0.2794)
			(end 0.51435 0.2794)
			(stroke
				(width 0.1)
				(type default)
			)
			(layer "B.Fab")
		)
		(pad "1" smd circle
			(at 0.40005 0 270)
			(size 0 0)
			(layers "B.Cu" "B.Mask" "B.Paste")
			(net "P3V3_AUX_FPGA_VCCIO1")
		)
		(pad "2" smd circle
			(at -0.40005 0 270)
			(size 0 0)
			(layers "B.Cu" "B.Mask" "B.Paste")
			(net "GND")
		)
		(zone
			(layer "B.Cu")
			(hatch none 0.5)
			(connect_pads
				(clearance 0)
			)
			(min_thickness 0.25)
			(keepout
				(tracks not_allowed)
				(vias allowed)
				(pads allowed)
				(copperpour not_allowed)
				(footprints allowed)
			)
			(placement
				(enabled no)
				(sheetname "")
			)
			(fill
				(thermal_gap 0.5)
				(thermal_bridge_width 0.5)
				(island_removal_mode 0)
			)
			(polygon
				(pts
					(xy 180.643276 -115.965986) (xy 180.701442 -115.874546) (xy 180.701442 -115.675156) (xy 180.643276 -115.584986)
					(xy 180.468016 -115.584986) (xy 180.409596 -115.675156) (xy 180.409596 -115.874546) (xy 180.467762 -115.965986)
				)
			)
		)
	)
	(footprint ""
		(layer "B.Cu")
		(at 73.902062 -181.81955 90)
		(property "Reference" "R299"
			(at 0 0 90)
			(layer "B.SilkS")
			(hide yes)
			(effects
				(font
					(size 1.27 1.27)
				)
				(justify mirror)
			)
		)
		(property "Value" ""
			(at 0 0 90)
			(layer "B.Fab")
			(effects
				(font
					(size 1.27 1.27)
				)
				(justify mirror)
			)
		)
		(duplicate_pad_numbers_are_jumpers no)
		(fp_line
			(start 0.7874 -0.4064)
			(end -0.7874 -0.4064)
			(stroke
				(width 0.1524)
				(type default)
			)
			(layer "B.SilkS")
		)
		(fp_line
			(start -0.7874 -0.4064)
			(end -0.7874 0.4064)
			(stroke
				(width 0.1524)
				(type default)
			)
			(layer "B.SilkS")
		)
		(fp_line
			(start 0.7874 0.4064)
			(end 0.7874 -0.4064)
			(stroke
				(width 0.1524)
				(type default)
			)
			(layer "B.SilkS")
		)
		(fp_line
			(start -0.7874 0.4064)
			(end 0.7874 0.4064)
			(stroke
				(width 0.1524)
				(type default)
			)
			(layer "B.SilkS")
		)
		(fp_line
			(start 0.67945 -0.305054)
			(end 0.12065 -0.305054)
			(stroke
				(width 0.1)
				(type default)
			)
			(layer "B.Fab")
		)
		(fp_line
			(start 0.12065 -0.305054)
			(end 0.12065 -0.2794)
			(stroke
				(width 0.1)
				(type default)
			)
			(layer "B.Fab")
		)
		(fp_line
			(start -0.12065 -0.3048)
			(end -0.67945 -0.3048)
			(stroke
				(width 0.1)
				(type default)
			)
			(layer "B.Fab")
		)
		(fp_line
			(start -0.67945 -0.3048)
			(end -0.67945 0.3048)
			(stroke
				(width 0.1)
				(type default)
			)
			(layer "B.Fab")
		)
		(fp_line
			(start 0.12065 -0.2794)
			(end -0.12065 -0.2794)
			(stroke
				(width 0.1)
				(type default)
			)
			(layer "B.Fab")
		)
		(fp_line
			(start -0.12065 -0.2794)
			(end -0.12065 -0.3048)
			(stroke
				(width 0.1)
				(type default)
			)
			(layer "B.Fab")
		)
		(fp_line
			(start 0.12065 0.2794)
			(end 0.12065 0.3048)
			(stroke
				(width 0.1)
				(type default)
			)
			(layer "B.Fab")
		)
		(fp_line
			(start -0.120396 0.2794)
			(end 0.12065 0.2794)
			(stroke
				(width 0.1)
				(type default)
			)
			(layer "B.Fab")
		)
		(fp_line
			(start 0.67945 0.3048)
			(end 0.67945 -0.305054)
			(stroke
				(width 0.1)
				(type default)
			)
			(layer "B.Fab")
		)
		(fp_line
			(start 0.12065 0.3048)
			(end 0.67945 0.3048)
			(stroke
				(width 0.1)
				(type default)
			)
			(layer "B.Fab")
		)
		(fp_line
			(start -0.120396 0.3048)
			(end -0.120396 0.2794)
			(stroke
				(width 0.1)
				(type default)
			)
			(layer "B.Fab")
		)
		(fp_line
			(start -0.67945 0.3048)
			(end -0.120396 0.3048)
			(stroke
				(width 0.1)
				(type default)
			)
			(layer "B.Fab")
		)
		(pad "1" smd circle
			(at 0.40005 0 270)
			(size 0 0)
			(layers "B.Cu" "B.Mask" "B.Paste")
			(net "H_CPU1_CATERR_LVC1_R_N")
		)
		(pad "2" smd circle
			(at -0.40005 0 270)
			(size 0 0)
			(layers "B.Cu" "B.Mask" "B.Paste")
			(net "H_CPU_CATERR_LVC1_R_N")
		)
	)
)
